# TIMECARD (Time Appliance Project (Time Card)) — schematic netlist excerpt (pin names and nets, part order shuffled) for the footprints in the layout excerpt that follows; sources: Cadence DE-HDL packaged netlist, KiCad conversion of R4006-B0001-02_R01.brd

R93  RESISTOR  33OHM 1%  pkg SMC_0402R_H016  page 21 : \1\ = R_MAC_BITEOUT ; \2\ = FPGA_IN_MAC_BITEOUT
R141  RESISTOR  0OHM -  pkg SMC_0402R_H016  page 30 : \1\ = XP1R2V_FPGA_PG ; \2\ = XP1R8V_EN_R

(kicad_pcb
	(version 20260206)
	(generator "pcbnew")
	(generator_version "10.0")
	(general
		(thickness 1.6)
		(legacy_teardrops no)
	)
	(paper "A4")
	(title_block
		(title "timecard-production-celestica-r4006 — R4006-B0001-02_R01.brd")
		(comment 1 "Time Appliance Project (Time Card) / footprints 656-657 of 1113")
	)
	(layers
		(0 "F.Cu" signal "TOP")
		(4 "In1.Cu" signal "L02_GND1")
		(6 "In2.Cu" signal "L03_SIG1")
		(8 "In3.Cu" signal "L04_GND2")
		(10 "In4.Cu" signal "L05_VCC1")
		(12 "In5.Cu" signal "L06_VCC2")
		(14 "In6.Cu" signal "L07_GND3")
		(16 "In7.Cu" signal "L08_SIG2")
		(18 "In8.Cu" signal "L09_GND4")
		(2 "B.Cu" signal "BOTTOM")
		(9 "F.Adhes" user "F.Adhesive")
		(11 "B.Adhes" user "B.Adhesive")
		(13 "F.Paste" user "Package Geometry/Pastemask Top")
		(15 "B.Paste" user "Package Geometry/Pastemask Bottom")
		(5 "F.SilkS" user "Ref Des/Silkscreen Top")
		(7 "B.SilkS" user "Ref Des/Silkscreen Bottom")
		(1 "F.Mask" user "Board Geometry/Soldermask Top")
		(3 "B.Mask" user "Board Geometry/Soldermask Bottom")
		(17 "Dwgs.User" user "User.Drawings")
		(19 "Cmts.User" user "User.Comments")
		(21 "Eco1.User" user "User.Eco1")
		(23 "Eco2.User" user "User.Eco2")
		(25 "Edge.Cuts" user "Board Geometry/Outline")
		(27 "Margin" user)
		(31 "F.CrtYd" user "Package Geometry/Place Bound Top")
		(29 "B.CrtYd" user "Package Geometry/Place Bound Bottom")
		(35 "F.Fab" user "Ref Des/Assembly Top")
		(33 "B.Fab" user "Ref Des/Assembly Bottom")
	)
	(footprint ""
		(layer "F.Cu")
		(at 124.1806 -68.7578 -90)
		(property "Reference" "R141"
			(at 2.5908 0.18923 90)
			(unlocked yes)
			(layer "F.SilkS")
			(effects
				(font
					(size 0.7874 0.5842)
					(thickness 0.1524)
				)
			)
		)
		(property "Value" "VAL*"
			(at 0.02032 2.13233 270)
			(unlocked yes)
			(layer "F.Fab")
			(hide yes)
			(effects
				(font
					(size 0.7874 0.5842)
					(thickness 0.1524)
				)
			)
		)
		(property "Device Type" "RESISTOR-G155-100R0-J0,0OHM,-"
			(at 0.008382 1.210564 270)
			(unlocked yes)
			(layer "F.Fab")
			(hide yes)
			(effects
				(font
					(size 0.7874 0.5842)
					(thickness 0.1524)
				)
			)
		)
		(property "User Part Number" "PARTNUM*"
			(at 0.02032 4.024884 270)
			(unlocked yes)
			(layer "Cmts.User")
			(hide yes)
			(effects
				(font
					(size 0.7874 0.5842)
					(thickness 0.1524)
				)
			)
		)
		(property "Tolerance" "TOL*"
			(at 0.044704 3.05435 270)
			(unlocked yes)
			(layer "Cmts.User")
			(hide yes)
			(effects
				(font
					(size 0.7874 0.5842)
					(thickness 0.1524)
				)
			)
		)
		(duplicate_pad_numbers_are_jumpers no)
		(fp_line
			(start -1.143 0.5588)
			(end 1.143 0.5588)
			(stroke
				(width 0.1)
				(type default)
			)
			(layer "F.SilkS")
		)
		(fp_line
			(start 1.143 0.5588)
			(end 1.143 -0.5588)
			(stroke
				(width 0.1)
				(type default)
			)
			(layer "F.SilkS")
		)
		(fp_line
			(start -1.143 -0.5588)
			(end -1.143 0.5588)
			(stroke
				(width 0.1)
				(type default)
			)
			(layer "F.SilkS")
		)
		(fp_line
			(start 1.143 -0.5588)
			(end -1.143 -0.5588)
			(stroke
				(width 0.1)
				(type default)
			)
			(layer "F.SilkS")
		)
		(fp_rect
			(start 1.143 0.5588)
			(end -1.143 -0.5588)
			(stroke
				(width 0)
				(type default)
			)
			(fill no)
			(layer "F.CrtYd")
		)
		(fp_line
			(start -0.508 0.3048)
			(end 0.508 0.3048)
			(stroke
				(width 0.1)
				(type default)
			)
			(layer "F.Fab")
		)
		(fp_line
			(start 0.508 0.3048)
			(end 0.508 -0.3048)
			(stroke
				(width 0.1)
				(type default)
			)
			(layer "F.Fab")
		)
		(fp_line
			(start -0.508 -0.3048)
			(end -0.508 0.3048)
			(stroke
				(width 0.1)
				(type default)
			)
			(layer "F.Fab")
		)
		(fp_line
			(start 0.508 -0.3048)
			(end -0.508 -0.3048)
			(stroke
				(width 0.1)
				(type default)
			)
			(layer "F.Fab")
		)
		(pad "1" smd rect
			(at -0.5334 0 270)
			(size 0.7112 0.6096)
			(layers "F.Cu" "F.Mask" "F.Paste")
			(net "XP1R2V_FPGA_PG")
		)
		(pad "2" smd rect
			(at 0.5334 0 270)
			(size 0.7112 0.6096)
			(layers "F.Cu" "F.Mask" "F.Paste")
			(net "XP1R8V_EN_R")
		)
		(zone
			(layer "F.Cu")
			(hatch none 0.5)
			(connect_pads
				(clearance 0)
			)
			(min_thickness 0.25)
			(keepout
				(tracks allowed)
				(vias not_allowed)
				(pads allowed)
				(copperpour not_allowed)
				(footprints allowed)
			)
			(placement
				(enabled no)
				(sheetname "")
			)
			(fill
				(thermal_gap 0.5)
				(thermal_bridge_width 0.5)
				(island_removal_mode 0)
			)
			(polygon
				(pts
					(xy 123.8758 -68.6816) (xy 124.4854 -68.6816) (xy 124.4854 -68.834) (xy 123.8758 -68.834)
				)
			)
		)
	)
	(footprint ""
		(layer "F.Cu")
		(at 124.587 -41.402 180)
		(property "Reference" "R93"
			(at -2.667 1.48463 0)
			(unlocked yes)
			(layer "F.SilkS")
			(effects
				(font
					(size 0.7874 0.5842)
					(thickness 0.1524)
				)
			)
		)
		(property "Value" "VAL*"
			(at 0.02032 2.13233 180)
			(unlocked yes)
			(layer "F.Fab")
			(hide yes)
			(effects
				(font
					(size 0.7874 0.5842)
					(thickness 0.1524)
				)
			)
		)
		(property "Tolerance" "TOL*"
			(at 0.044704 3.05435 180)
			(unlocked yes)
			(layer "Cmts.User")
			(hide yes)
			(effects
				(font
					(size 0.7874 0.5842)
					(thickness 0.1524)
				)
			)
		)
		(property "User Part Number" "PARTNUM*"
			(at 0.02032 4.024884 180)
			(unlocked yes)
			(layer "Cmts.User")
			(hide yes)
			(effects
				(font
					(size 0.7874 0.5842)
					(thickness 0.1524)
				)
			)
		)
		(property "Device Type" "RESISTOR-G155-133R0-01,33OHM,1%"
			(at 0.008382 1.210564 180)
			(unlocked yes)
			(layer "F.Fab")
			(hide yes)
			(effects
				(font
					(size 0.7874 0.5842)
					(thickness 0.1524)
				)
			)
		)
		(duplicate_pad_numbers_are_jumpers no)
		(fp_line
			(start 1.143 0.5588)
			(end 1.143 -0.5588)
			(stroke
				(width 0.1)
				(type default)
			)
			(layer "F.SilkS")
		)
		(fp_line
			(start 1.143 -0.5588)
			(end -1.143 -0.5588)
			(stroke
				(width 0.1)
				(type default)
			)
			(layer "F.SilkS")
		)
		(fp_line
			(start -1.143 0.5588)
			(end 1.143 0.5588)
			(stroke
				(width 0.1)
				(type default)
			)
			(layer "F.SilkS")
		)
		(fp_line
			(start -1.143 -0.5588)
			(end -1.143 0.5588)
			(stroke
				(width 0.1)
				(type default)
			)
			(layer "F.SilkS")
		)
		(fp_rect
			(start 1.143 -0.5588)
			(end -1.143 0.5588)
			(stroke
				(width 0)
				(type default)
			)
			(fill no)
			(layer "F.CrtYd")
		)
		(fp_line
			(start 0.508 0.3048)
			(end 0.508 -0.3048)
			(stroke
				(width 0.1)
				(type default)
			)
			(layer "F.Fab")
		)
		(fp_line
			(start 0.508 -0.3048)
			(end -0.508 -0.3048)
			(stroke
				(width 0.1)
				(type default)
			)
			(layer "F.Fab")
		)
		(fp_line
			(start -0.508 0.3048)
			(end 0.508 0.3048)
			(stroke
				(width 0.1)
				(type default)
			)
			(layer "F.Fab")
		)
		(fp_line
			(start -0.508 -0.3048)
			(end -0.508 0.3048)
			(stroke
				(width 0.1)
				(type default)
			)
			(layer "F.Fab")
		)
		(pad "1" smd rect
			(at -0.5334 0 180)
			(size 0.7112 0.6096)
			(layers "F.Cu" "F.Mask" "F.Paste")
			(net "R_MAC_BITEOUT")
		)
		(pad "2" smd rect
			(at 0.5334 0 180)
			(size 0.7112 0.6096)
			(layers "F.Cu" "F.Mask" "F.Paste")
			(net "FPGA_IN_MAC_BITEOUT")
		)
		(zone
			(layer "F.Cu")
			(hatch none 0.5)
			(connect_pads
				(clearance 0)
			)
			(min_thickness 0.25)
			(keepout
				(tracks allowed)
				(vias not_allowed)
				(pads allowed)
				(copperpour not_allowed)
				(footprints allowed)
			)
			(placement
				(enabled no)
				(sheetname "")
			)
			(fill
				(thermal_gap 0.5)
				(thermal_bridge_width 0.5)
				(island_removal_mode 0)
			)
			(polygon
				(pts
					(xy 124.5108 -41.0972) (xy 124.6632 -41.0972) (xy 124.6632 -41.7068) (xy 124.5108 -41.7068)
				)
			)
		)
	)
)
